# SCM (Grand Teton) — schematic netlist excerpt (pin names and nets, part order shuffled) for the footprints in the layout excerpt that follows; sources: Cadence DE-HDL packaged netlist, KiCad conversion of 12092022_DA0F0TMDCD0_F0T_Management_Board_D_brd_V3_OCP.brd

R241  Q_RES  4.7K 1% CHIP  pkg 0402LF  page 13 : A = P3V3_AUX ; B = PU_SPI1ABR
R179  Q_RES  33.2 1% CHIP  pkg 0402LF  page 13 : A = SPI_BMC_MOSI_IO0_R ; B = SPI_BMC_BOOT_MOSI

(kicad_pcb
	(version 20260206)
	(generator "pcbnew")
	(generator_version "10.0")
	(general
		(thickness 1.6)
		(legacy_teardrops no)
	)
	(paper "A4")
	(title_block
		(title "12092022_DA0F0TMDCD0_F0T_Management_Board_D_brd_V3_OCP.brd")
		(comment 1 "Grand Teton / footprints 1382-1383 of 1440")
	)
	(layers
		(0 "F.Cu" signal "TOP")
		(4 "In1.Cu" signal "GND")
		(6 "In2.Cu" signal "IN1")
		(8 "In3.Cu" signal "GND1")
		(10 "In4.Cu" signal "IN2")
		(12 "In5.Cu" signal "VCC")
		(14 "In6.Cu" signal "VCC1")
		(16 "In7.Cu" signal "IN3")
		(18 "In8.Cu" signal "GND2")
		(20 "In9.Cu" signal "IN4")
		(22 "In10.Cu" signal "GND3")
		(2 "B.Cu" signal "BOTTOM")
		(9 "F.Adhes" user "F.Adhesive")
		(11 "B.Adhes" user "B.Adhesive")
		(13 "F.Paste" user "Package Geometry/Pastemask Top")
		(15 "B.Paste" user "Package Geometry/Pastemask Bottom")
		(5 "F.SilkS" user "Ref Des/Silkscreen Top")
		(7 "B.SilkS" user "Ref Des/Silkscreen Bottom")
		(1 "F.Mask" user "Board Geometry/Soldermask Top")
		(3 "B.Mask" user "Board Geometry/Soldermask Bottom")
		(17 "Dwgs.User" user "User.Drawings")
		(19 "Cmts.User" user "User.Comments")
		(21 "Eco1.User" user "User.Eco1")
		(23 "Eco2.User" user "User.Eco2")
		(25 "Edge.Cuts" user "Board Geometry/Outline")
		(27 "Margin" user)
		(31 "F.CrtYd" user "Package Geometry/Place Bound Top")
		(29 "B.CrtYd" user "Package Geometry/Place Bound Bottom")
		(35 "F.Fab" user "Ref Des/Assembly Top")
		(33 "B.Fab" user "Ref Des/Assembly Bottom")
	)
	(footprint ""
		(layer "B.Cu")
		(at 54.16423 -61.0616 -90)
		(property "Reference" "R179"
			(at 0 0 90)
			(layer "B.SilkS")
			(hide yes)
			(effects
				(font
					(size 1.27 1.27)
				)
				(justify mirror)
			)
		)
		(property "Value" ""
			(at 0 0 90)
			(layer "B.Fab")
			(effects
				(font
					(size 1.27 1.27)
				)
				(justify mirror)
			)
		)
		(duplicate_pad_numbers_are_jumpers no)
		(fp_line
			(start -0.7874 0.4064)
			(end 0.7874 0.4064)
			(stroke
				(width 0.1524)
				(type default)
			)
			(layer "B.SilkS")
		)
		(fp_line
			(start 0.7874 0.4064)
			(end 0.7874 -0.4064)
			(stroke
				(width 0.1524)
				(type default)
			)
			(layer "B.SilkS")
		)
		(fp_line
			(start -0.7874 -0.4064)
			(end -0.7874 0.4064)
			(stroke
				(width 0.1524)
				(type default)
			)
			(layer "B.SilkS")
		)
		(fp_line
			(start 0.7874 -0.4064)
			(end -0.7874 -0.4064)
			(stroke
				(width 0.1524)
				(type default)
			)
			(layer "B.SilkS")
		)
		(fp_line
			(start -0.67945 0.3048)
			(end -0.120396 0.3048)
			(stroke
				(width 0.1)
				(type default)
			)
			(layer "B.Fab")
		)
		(fp_line
			(start -0.120396 0.3048)
			(end -0.120396 0.2794)
			(stroke
				(width 0.1)
				(type default)
			)
			(layer "B.Fab")
		)
		(fp_line
			(start 0.12065 0.3048)
			(end 0.67945 0.3048)
			(stroke
				(width 0.1)
				(type default)
			)
			(layer "B.Fab")
		)
		(fp_line
			(start 0.67945 0.3048)
			(end 0.67945 -0.305054)
			(stroke
				(width 0.1)
				(type default)
			)
			(layer "B.Fab")
		)
		(fp_line
			(start -0.120396 0.2794)
			(end 0.12065 0.2794)
			(stroke
				(width 0.1)
				(type default)
			)
			(layer "B.Fab")
		)
		(fp_line
			(start 0.12065 0.2794)
			(end 0.12065 0.3048)
			(stroke
				(width 0.1)
				(type default)
			)
			(layer "B.Fab")
		)
		(fp_line
			(start -0.12065 -0.2794)
			(end -0.12065 -0.3048)
			(stroke
				(width 0.1)
				(type default)
			)
			(layer "B.Fab")
		)
		(fp_line
			(start 0.12065 -0.2794)
			(end -0.12065 -0.2794)
			(stroke
				(width 0.1)
				(type default)
			)
			(layer "B.Fab")
		)
		(fp_line
			(start -0.67945 -0.3048)
			(end -0.67945 0.3048)
			(stroke
				(width 0.1)
				(type default)
			)
			(layer "B.Fab")
		)
		(fp_line
			(start -0.12065 -0.3048)
			(end -0.67945 -0.3048)
			(stroke
				(width 0.1)
				(type default)
			)
			(layer "B.Fab")
		)
		(fp_line
			(start 0.12065 -0.305054)
			(end 0.12065 -0.2794)
			(stroke
				(width 0.1)
				(type default)
			)
			(layer "B.Fab")
		)
		(fp_line
			(start 0.67945 -0.305054)
			(end 0.12065 -0.305054)
			(stroke
				(width 0.1)
				(type default)
			)
			(layer "B.Fab")
		)
		(pad "1" smd circle
			(at 0.40005 0 90)
			(size 0 0)
			(layers "B.Cu" "B.Mask" "B.Paste")
			(net "SPI_BMC_MOSI_IO0_R")
		)
		(pad "2" smd circle
			(at -0.40005 0 90)
			(size 0 0)
			(layers "B.Cu" "B.Mask" "B.Paste")
			(net "SPI_BMC_BOOT_MOSI")
		)
	)
	(footprint ""
		(layer "B.Cu")
		(at 58.23331 -66.147442 -90)
		(property "Reference" "R241"
			(at 0 0 90)
			(layer "B.SilkS")
			(hide yes)
			(effects
				(font
					(size 1.27 1.27)
				)
				(justify mirror)
			)
		)
		(property "Value" ""
			(at 0 0 90)
			(layer "B.Fab")
			(effects
				(font
					(size 1.27 1.27)
				)
				(justify mirror)
			)
		)
		(duplicate_pad_numbers_are_jumpers no)
		(fp_line
			(start -0.7874 0.4064)
			(end 0.7874 0.4064)
			(stroke
				(width 0.1524)
				(type default)
			)
			(layer "B.SilkS")
		)
		(fp_line
			(start 0.7874 0.4064)
			(end 0.7874 -0.4064)
			(stroke
				(width 0.1524)
				(type default)
			)
			(layer "B.SilkS")
		)
		(fp_line
			(start -0.7874 -0.4064)
			(end -0.7874 0.4064)
			(stroke
				(width 0.1524)
				(type default)
			)
			(layer "B.SilkS")
		)
		(fp_line
			(start 0.7874 -0.4064)
			(end -0.7874 -0.4064)
			(stroke
				(width 0.1524)
				(type default)
			)
			(layer "B.SilkS")
		)
		(fp_line
			(start -0.67945 0.3048)
			(end -0.120396 0.3048)
			(stroke
				(width 0.1)
				(type default)
			)
			(layer "B.Fab")
		)
		(fp_line
			(start -0.120396 0.3048)
			(end -0.120396 0.2794)
			(stroke
				(width 0.1)
				(type default)
			)
			(layer "B.Fab")
		)
		(fp_line
			(start 0.12065 0.3048)
			(end 0.67945 0.3048)
			(stroke
				(width 0.1)
				(type default)
			)
			(layer "B.Fab")
		)
		(fp_line
			(start 0.67945 0.3048)
			(end 0.67945 -0.305054)
			(stroke
				(width 0.1)
				(type default)
			)
			(layer "B.Fab")
		)
		(fp_line
			(start -0.120396 0.2794)
			(end 0.12065 0.2794)
			(stroke
				(width 0.1)
				(type default)
			)
			(layer "B.Fab")
		)
		(fp_line
			(start 0.12065 0.2794)
			(end 0.12065 0.3048)
			(stroke
				(width 0.1)
				(type default)
			)
			(layer "B.Fab")
		)
		(fp_line
			(start -0.12065 -0.2794)
			(end -0.12065 -0.3048)
			(stroke
				(width 0.1)
				(type default)
			)
			(layer "B.Fab")
		)
		(fp_line
			(start 0.12065 -0.2794)
			(end -0.12065 -0.2794)
			(stroke
				(width 0.1)
				(type default)
			)
			(layer "B.Fab")
		)
		(fp_line
			(start -0.67945 -0.3048)
			(end -0.67945 0.3048)
			(stroke
				(width 0.1)
				(type default)
			)
			(layer "B.Fab")
		)
		(fp_line
			(start -0.12065 -0.3048)
			(end -0.67945 -0.3048)
			(stroke
				(width 0.1)
				(type default)
			)
			(layer "B.Fab")
		)
		(fp_line
			(start 0.12065 -0.305054)
			(end 0.12065 -0.2794)
			(stroke
				(width 0.1)
				(type default)
			)
			(layer "B.Fab")
		)
		(fp_line
			(start 0.67945 -0.305054)
			(end 0.12065 -0.305054)
			(stroke
				(width 0.1)
				(type default)
			)
			(layer "B.Fab")
		)
		(pad "1" smd circle
			(at 0.40005 0 90)
			(size 0 0)
			(layers "B.Cu" "B.Mask" "B.Paste")
			(net "P3V3_AUX")
		)
		(pad "2" smd circle
			(at -0.40005 0 90)
			(size 0 0)
			(layers "B.Cu" "B.Mask" "B.Paste")
			(net "PU_SPI1ABR")
		)
	)
)
